(kicad_pcb
	(version 20260206)
	(generator "pcbnew")
	(generator_version "10.0")
	(general
		(thickness 1.6)
		(legacy_teardrops no)
	)
	(paper "A4")
	(title_block
		(title "01162023_DA0F0TEBIF0_F0T_Expander_BD_F_brd_V02_OCP.brd")
		(comment 1 "Grand Teton / footprints 6838-6843 of 9728")
	)
	(layers
		(0 "F.Cu" signal "TOP")
		(4 "In1.Cu" signal "GND")
		(6 "In2.Cu" signal "VCC")
		(8 "In3.Cu" signal "VCC1")
		(10 "In4.Cu" signal "GND1")
		(12 "In5.Cu" signal "IN1")
		(14 "In6.Cu" signal "GND2")
		(16 "In7.Cu" signal "IN2")
		(18 "In8.Cu" signal "GND3")
		(20 "In9.Cu" signal "IN3")
		(22 "In10.Cu" signal "GND4")
		(24 "In11.Cu" signal "IN4")
		(26 "In12.Cu" signal "GND5")
		(28 "In13.Cu" signal "IN5")
		(30 "In14.Cu" signal "GND6")
		(32 "In15.Cu" signal "IN6")
		(34 "In16.Cu" signal "GND7")
		(2 "B.Cu" signal "BOTTOM")
		(9 "F.Adhes" user "F.Adhesive")
		(11 "B.Adhes" user "B.Adhesive")
		(13 "F.Paste" user "Package Geometry/Pastemask Top")
		(15 "B.Paste" user "Package Geometry/Pastemask Bottom")
		(5 "F.SilkS" user "Ref Des/Silkscreen Top")
		(7 "B.SilkS" user "Ref Des/Silkscreen Bottom")
		(1 "F.Mask" user "Board Geometry/Soldermask Top")
		(3 "B.Mask" user "Board Geometry/Soldermask Bottom")
		(17 "Dwgs.User" user "User.Drawings")
		(19 "Cmts.User" user "User.Comments")
		(21 "Eco1.User" user "User.Eco1")
		(23 "Eco2.User" user "User.Eco2")
		(25 "Edge.Cuts" user "Board Geometry/Outline")
		(27 "Margin" user)
		(31 "F.CrtYd" user "Package Geometry/Place Bound Top")
		(29 "B.CrtYd" user "Package Geometry/Place Bound Bottom")
		(35 "F.Fab" user "Ref Des/Assembly Top")
		(33 "B.Fab" user "Ref Des/Assembly Bottom")
	)
	(footprint ""
		(layer "F.Cu")
		(at 262.353298 -281.789632)
		(property "Reference" "L128"
			(at 0 0 0)
			(layer "F.SilkS")
			(hide yes)
			(effects
				(font
					(size 1.27 1.27)
				)
			)
		)
		(property "Value" ""
			(at 0 0 0)
			(layer "F.Fab")
			(effects
				(font
					(size 1.27 1.27)
				)
			)
		)
		(duplicate_pad_numbers_are_jumpers no)
		(fp_line
			(start -1.63576 -0.8128)
			(end -1.63576 0.8128)
			(stroke
				(width 0.1524)
				(type default)
			)
			(layer "F.SilkS")
		)
		(fp_line
			(start -1.63576 -0.8128)
			(end 1.63576 -0.8128)
			(stroke
				(width 0.1524)
				(type default)
			)
			(layer "F.SilkS")
		)
		(fp_line
			(start 1.63576 -0.8128)
			(end 1.63576 0.8128)
			(stroke
				(width 0.1524)
				(type default)
			)
			(layer "F.SilkS")
		)
		(fp_line
			(start 1.63576 0.8128)
			(end -1.63576 0.8128)
			(stroke
				(width 0.1524)
				(type default)
			)
			(layer "F.SilkS")
		)
		(fp_line
			(start -1.56083 -0.738632)
			(end -1.56083 0.7366)
			(stroke
				(width 0.1)
				(type default)
			)
			(layer "F.Fab")
		)
		(fp_line
			(start -1.56083 0.7366)
			(end -1.524 0.7366)
			(stroke
				(width 0.1)
				(type default)
			)
			(layer "F.Fab")
		)
		(fp_line
			(start -1.524 0.7366)
			(end 1.524 0.7366)
			(stroke
				(width 0.1)
				(type default)
			)
			(layer "F.Fab")
		)
		(fp_line
			(start 1.524 0.7366)
			(end 1.560576 0.7366)
			(stroke
				(width 0.1)
				(type default)
			)
			(layer "F.Fab")
		)
		(fp_line
			(start 1.560576 -0.738632)
			(end -1.56083 -0.738632)
			(stroke
				(width 0.1)
				(type default)
			)
			(layer "F.Fab")
		)
		(fp_line
			(start 1.560576 0.7366)
			(end 1.560576 -0.738632)
			(stroke
				(width 0.1)
				(type default)
			)
			(layer "F.Fab")
		)
		(pad "1" smd rect
			(at -0.94996 0 180)
			(size 1.1176 1.3716)
			(layers "F.Cu" "F.Mask" "F.Paste")
			(net "P1V8_PLL0_PEX2")
		)
		(pad "2" smd rect
			(at 0.94996 0 180)
			(size 1.1176 1.3716)
			(layers "F.Cu" "F.Mask" "F.Paste")
			(net "SYSPLL_VDDA18_PEX2")
		)
	)
	(footprint ""
		(layer "F.Cu")
		(at 219.223844 -96.139 90)
		(property "Reference" "R713"
			(at 0 0 90)
			(layer "F.SilkS")
			(hide yes)
			(effects
				(font
					(size 1.27 1.27)
				)
			)
		)
		(property "Value" ""
			(at 0 0 90)
			(layer "F.Fab")
			(effects
				(font
					(size 1.27 1.27)
				)
			)
		)
		(duplicate_pad_numbers_are_jumpers no)
		(fp_line
			(start 0.7874 -0.4064)
			(end 0.7874 0.4064)
			(stroke
				(width 0.1524)
				(type default)
			)
			(layer "F.SilkS")
		)
		(fp_line
			(start -0.7874 -0.4064)
			(end 0.7874 -0.4064)
			(stroke
				(width 0.1524)
				(type default)
			)
			(layer "F.SilkS")
		)
		(fp_line
			(start 0.7874 0.4064)
			(end -0.7874 0.4064)
			(stroke
				(width 0.1524)
				(type default)
			)
			(layer "F.SilkS")
		)
		(fp_line
			(start -0.7874 0.4064)
			(end -0.7874 -0.4064)
			(stroke
				(width 0.1524)
				(type default)
			)
			(layer "F.SilkS")
		)
		(fp_line
			(start -0.12065 -0.305054)
			(end -0.12065 -0.2794)
			(stroke
				(width 0.1)
				(type default)
			)
			(layer "F.Fab")
		)
		(fp_line
			(start -0.67945 -0.305054)
			(end -0.12065 -0.305054)
			(stroke
				(width 0.1)
				(type default)
			)
			(layer "F.Fab")
		)
		(fp_line
			(start 0.67945 -0.3048)
			(end 0.67945 0.3048)
			(stroke
				(width 0.1)
				(type default)
			)
			(layer "F.Fab")
		)
		(fp_line
			(start 0.12065 -0.3048)
			(end 0.67945 -0.3048)
			(stroke
				(width 0.1)
				(type default)
			)
			(layer "F.Fab")
		)
		(fp_line
			(start 0.12065 -0.2794)
			(end 0.12065 -0.3048)
			(stroke
				(width 0.1)
				(type default)
			)
			(layer "F.Fab")
		)
		(fp_line
			(start -0.12065 -0.2794)
			(end 0.12065 -0.2794)
			(stroke
				(width 0.1)
				(type default)
			)
			(layer "F.Fab")
		)
		(fp_line
			(start 0.120396 0.2794)
			(end -0.12065 0.2794)
			(stroke
				(width 0.1)
				(type default)
			)
			(layer "F.Fab")
		)
		(fp_line
			(start -0.12065 0.2794)
			(end -0.12065 0.3048)
			(stroke
				(width 0.1)
				(type default)
			)
			(layer "F.Fab")
		)
		(fp_line
			(start 0.67945 0.3048)
			(end 0.120396 0.3048)
			(stroke
				(width 0.1)
				(type default)
			)
			(layer "F.Fab")
		)
		(fp_line
			(start 0.120396 0.3048)
			(end 0.120396 0.2794)
			(stroke
				(width 0.1)
				(type default)
			)
			(layer "F.Fab")
		)
		(fp_line
			(start -0.12065 0.3048)
			(end -0.67945 0.3048)
			(stroke
				(width 0.1)
				(type default)
			)
			(layer "F.Fab")
		)
		(fp_line
			(start -0.67945 0.3048)
			(end -0.67945 -0.305054)
			(stroke
				(width 0.1)
				(type default)
			)
			(layer "F.Fab")
		)
		(pad "1" smd circle
			(at -0.40005 0 90)
			(size 0 0)
			(layers "F.Cu" "F.Mask" "F.Paste")
			(net "P3V3_AUX")
		)
		(pad "2" smd circle
			(at 0.40005 0 90)
			(size 0 0)
			(layers "F.Cu" "F.Mask" "F.Paste")
			(net "NIC_ADC_ALERT_N")
		)
	)
	(footprint ""
		(layer "F.Cu")
		(at 336.042 -183.007 180)
		(property "Reference" "R4739"
			(at 0 0 180)
			(layer "F.SilkS")
			(hide yes)
			(effects
				(font
					(size 1.27 1.27)
				)
			)
		)
		(property "Value" ""
			(at 0 0 180)
			(layer "F.Fab")
			(effects
				(font
					(size 1.27 1.27)
				)
			)
		)
		(duplicate_pad_numbers_are_jumpers no)
		(fp_line
			(start 0.7874 0.4064)
			(end -0.7874 0.4064)
			(stroke
				(width 0.1524)
				(type default)
			)
			(layer "F.SilkS")
		)
		(fp_line
			(start 0.7874 -0.4064)
			(end 0.7874 0.4064)
			(stroke
				(width 0.1524)
				(type default)
			)
			(layer "F.SilkS")
		)
		(fp_line
			(start -0.7874 0.4064)
			(end -0.7874 -0.4064)
			(stroke
				(width 0.1524)
				(type default)
			)
			(layer "F.SilkS")
		)
		(fp_line
			(start -0.7874 -0.4064)
			(end 0.7874 -0.4064)
			(stroke
				(width 0.1524)
				(type default)
			)
			(layer "F.SilkS")
		)
		(fp_line
			(start 0.67945 0.3048)
			(end 0.120396 0.3048)
			(stroke
				(width 0.1)
				(type default)
			)
			(layer "F.Fab")
		)
		(fp_line
			(start 0.67945 -0.3048)
			(end 0.67945 0.3048)
			(stroke
				(width 0.1)
				(type default)
			)
			(layer "F.Fab")
		)
		(fp_line
			(start 0.12065 -0.2794)
			(end 0.12065 -0.3048)
			(stroke
				(width 0.1)
				(type default)
			)
			(layer "F.Fab")
		)
		(fp_line
			(start 0.12065 -0.3048)
			(end 0.67945 -0.3048)
			(stroke
				(width 0.1)
				(type default)
			)
			(layer "F.Fab")
		)
		(fp_line
			(start 0.120396 0.3048)
			(end 0.120396 0.2794)
			(stroke
				(width 0.1)
				(type default)
			)
			(layer "F.Fab")
		)
		(fp_line
			(start 0.120396 0.2794)
			(end -0.12065 0.2794)
			(stroke
				(width 0.1)
				(type default)
			)
			(layer "F.Fab")
		)
		(fp_line
			(start -0.12065 0.3048)
			(end -0.67945 0.3048)
			(stroke
				(width 0.1)
				(type default)
			)
			(layer "F.Fab")
		)
		(fp_line
			(start -0.12065 0.2794)
			(end -0.12065 0.3048)
			(stroke
				(width 0.1)
				(type default)
			)
			(layer "F.Fab")
		)
		(fp_line
			(start -0.12065 -0.2794)
			(end 0.12065 -0.2794)
			(stroke
				(width 0.1)
				(type default)
			)
			(layer "F.Fab")
		)
		(fp_line
			(start -0.12065 -0.305054)
			(end -0.12065 -0.2794)
			(stroke
				(width 0.1)
				(type default)
			)
			(layer "F.Fab")
		)
		(fp_line
			(start -0.67945 0.3048)
			(end -0.67945 -0.305054)
			(stroke
				(width 0.1)
				(type default)
			)
			(layer "F.Fab")
		)
		(fp_line
			(start -0.67945 -0.305054)
			(end -0.12065 -0.305054)
			(stroke
				(width 0.1)
				(type default)
			)
			(layer "F.Fab")
		)
		(pad "1" smd circle
			(at -0.40005 0 180)
			(size 0 0)
			(layers "F.Cu" "F.Mask" "F.Paste")
			(net "SSD8_PEX_PWR_EN_R")
		)
		(pad "2" smd circle
			(at 0.40005 0 180)
			(size 0 0)
			(layers "F.Cu" "F.Mask" "F.Paste")
			(net "GND")
		)
	)
	(footprint ""
		(layer "F.Cu")
		(at 376.809 -173.13402)
		(property "Reference" "R4666"
			(at 0 0 0)
			(layer "F.SilkS")
			(hide yes)
			(effects
				(font
					(size 1.27 1.27)
				)
			)
		)
		(property "Value" ""
			(at 0 0 0)
			(layer "F.Fab")
			(effects
				(font
					(size 1.27 1.27)
				)
			)
		)
		(duplicate_pad_numbers_are_jumpers no)
		(fp_line
			(start -0.7874 -0.4064)
			(end 0.7874 -0.4064)
			(stroke
				(width 0.1524)
				(type default)
			)
			(layer "F.SilkS")
		)
		(fp_line
			(start -0.7874 0.4064)
			(end -0.7874 -0.4064)
			(stroke
				(width 0.1524)
				(type default)
			)
			(layer "F.SilkS")
		)
		(fp_line
			(start 0.7874 -0.4064)
			(end 0.7874 0.4064)
			(stroke
				(width 0.1524)
				(type default)
			)
			(layer "F.SilkS")
		)
		(fp_line
			(start 0.7874 0.4064)
			(end -0.7874 0.4064)
			(stroke
				(width 0.1524)
				(type default)
			)
			(layer "F.SilkS")
		)
		(fp_line
			(start -0.67945 -0.305054)
			(end -0.12065 -0.305054)
			(stroke
				(width 0.1)
				(type default)
			)
			(layer "F.Fab")
		)
		(fp_line
			(start -0.67945 0.3048)
			(end -0.67945 -0.305054)
			(stroke
				(width 0.1)
				(type default)
			)
			(layer "F.Fab")
		)
		(fp_line
			(start -0.12065 -0.305054)
			(end -0.12065 -0.2794)
			(stroke
				(width 0.1)
				(type default)
			)
			(layer "F.Fab")
		)
		(fp_line
			(start -0.12065 -0.2794)
			(end 0.12065 -0.2794)
			(stroke
				(width 0.1)
				(type default)
			)
			(layer "F.Fab")
		)
		(fp_line
			(start -0.12065 0.2794)
			(end -0.12065 0.3048)
			(stroke
				(width 0.1)
				(type default)
			)
			(layer "F.Fab")
		)
		(fp_line
			(start -0.12065 0.3048)
			(end -0.67945 0.3048)
			(stroke
				(width 0.1)
				(type default)
			)
			(layer "F.Fab")
		)
		(fp_line
			(start 0.120396 0.2794)
			(end -0.12065 0.2794)
			(stroke
				(width 0.1)
				(type default)
			)
			(layer "F.Fab")
		)
		(fp_line
			(start 0.120396 0.3048)
			(end 0.120396 0.2794)
			(stroke
				(width 0.1)
				(type default)
			)
			(layer "F.Fab")
		)
		(fp_line
			(start 0.12065 -0.3048)
			(end 0.67945 -0.3048)
			(stroke
				(width 0.1)
				(type default)
			)
			(layer "F.Fab")
		)
		(fp_line
			(start 0.12065 -0.2794)
			(end 0.12065 -0.3048)
			(stroke
				(width 0.1)
				(type default)
			)
			(layer "F.Fab")
		)
		(fp_line
			(start 0.67945 -0.3048)
			(end 0.67945 0.3048)
			(stroke
				(width 0.1)
				(type default)
			)
			(layer "F.Fab")
		)
		(fp_line
			(start 0.67945 0.3048)
			(end 0.120396 0.3048)
			(stroke
				(width 0.1)
				(type default)
			)
			(layer "F.Fab")
		)
		(pad "1" smd circle
			(at -0.40005 0)
			(size 0 0)
			(layers "F.Cu" "F.Mask" "F.Paste")
			(net "P3V3_AUX")
		)
		(pad "2" smd circle
			(at 0.40005 0)
			(size 0 0)
			(layers "F.Cu" "F.Mask" "F.Paste")
			(net "NIC3_PEX_PWR_EN_R")
		)
	)
	(footprint ""
		(layer "F.Cu")
		(at 380.690882 -230.43896 180)
		(property "Reference" "C2578"
			(at 0 0 180)
			(layer "F.SilkS")
			(hide yes)
			(effects
				(font
					(size 1.27 1.27)
				)
			)
		)
		(property "Value" ""
			(at 0 0 180)
			(layer "F.Fab")
			(effects
				(font
					(size 1.27 1.27)
				)
			)
		)
		(duplicate_pad_numbers_are_jumpers no)
		(fp_line
			(start 0.7874 0.4064)
			(end -0.7874 0.4064)
			(stroke
				(width 0.1524)
				(type default)
			)
			(layer "F.SilkS")
		)
		(fp_line
			(start 0.7874 -0.4064)
			(end 0.7874 0.4064)
			(stroke
				(width 0.1524)
				(type default)
			)
			(layer "F.SilkS")
		)
		(fp_line
			(start -0.7874 0.4064)
			(end -0.7874 -0.4064)
			(stroke
				(width 0.1524)
				(type default)
			)
			(layer "F.SilkS")
		)
		(fp_line
			(start -0.7874 -0.4064)
			(end 0.7874 -0.4064)
			(stroke
				(width 0.1524)
				(type default)
			)
			(layer "F.SilkS")
		)
		(fp_line
			(start 0.67945 0.3048)
			(end 0.120396 0.3048)
			(stroke
				(width 0.1)
				(type default)
			)
			(layer "F.Fab")
		)
		(fp_line
			(start 0.67945 -0.3048)
			(end 0.67945 0.3048)
			(stroke
				(width 0.1)
				(type default)
			)
			(layer "F.Fab")
		)
		(fp_line
			(start 0.12065 -0.2794)
			(end 0.12065 -0.3048)
			(stroke
				(width 0.1)
				(type default)
			)
			(layer "F.Fab")
		)
		(fp_line
			(start 0.12065 -0.3048)
			(end 0.67945 -0.3048)
			(stroke
				(width 0.1)
				(type default)
			)
			(layer "F.Fab")
		)
		(fp_line
			(start 0.120396 0.3048)
			(end 0.120396 0.2794)
			(stroke
				(width 0.1)
				(type default)
			)
			(layer "F.Fab")
		)
		(fp_line
			(start 0.120396 0.2794)
			(end -0.12065 0.2794)
			(stroke
				(width 0.1)
				(type default)
			)
			(layer "F.Fab")
		)
		(fp_line
			(start -0.12065 0.3048)
			(end -0.67945 0.3048)
			(stroke
				(width 0.1)
				(type default)
			)
			(layer "F.Fab")
		)
		(fp_line
			(start -0.12065 0.2794)
			(end -0.12065 0.3048)
			(stroke
				(width 0.1)
				(type default)
			)
			(layer "F.Fab")
		)
		(fp_line
			(start -0.12065 -0.2794)
			(end 0.12065 -0.2794)
			(stroke
				(width 0.1)
				(type default)
			)
			(layer "F.Fab")
		)
		(fp_line
			(start -0.12065 -0.305054)
			(end -0.12065 -0.2794)
			(stroke
				(width 0.1)
				(type default)
			)
			(layer "F.Fab")
		)
		(fp_line
			(start -0.67945 0.3048)
			(end -0.67945 -0.305054)
			(stroke
				(width 0.1)
				(type default)
			)
			(layer "F.Fab")
		)
		(fp_line
			(start -0.67945 -0.305054)
			(end -0.12065 -0.305054)
			(stroke
				(width 0.1)
				(type default)
			)
			(layer "F.Fab")
		)
		(pad "1" smd circle
			(at -0.40005 0 180)
			(size 0 0)
			(layers "F.Cu" "F.Mask" "F.Paste")
			(net "OSC_SDB_IN")
		)
		(pad "2" smd circle
			(at 0.40005 0 180)
			(size 0 0)
			(layers "F.Cu" "F.Mask" "F.Paste")
			(net "GND")
		)
	)
	(footprint ""
		(layer "F.Cu")
		(at 359.396538 -308.438296 -90)
		(property "Reference" "C4360"
			(at 0 0 270)
			(layer "F.SilkS")
			(hide yes)
			(effects
				(font
					(size 1.27 1.27)
				)
			)
		)
		(property "Value" ""
			(at 0 0 270)
			(layer "F.Fab")
			(effects
				(font
					(size 1.27 1.27)
				)
			)
		)
		(duplicate_pad_numbers_are_jumpers no)
		(fp_line
			(start -1.2954 0.5842)
			(end -1.2954 -0.5842)
			(stroke
				(width 0.1524)
				(type default)
			)
			(layer "F.SilkS")
		)
		(fp_line
			(start 1.2954 0.5842)
			(end -1.2954 0.5842)
			(stroke
				(width 0.1524)
				(type default)
			)
			(layer "F.SilkS")
		)
		(fp_line
			(start -1.2954 -0.5842)
			(end 1.2954 -0.5842)
			(stroke
				(width 0.1524)
				(type default)
			)
			(layer "F.SilkS")
		)
		(fp_line
			(start 1.2954 -0.5842)
			(end 1.2954 0.5842)
			(stroke
				(width 0.1524)
				(type default)
			)
			(layer "F.SilkS")
		)
		(fp_line
			(start -0.8636 0.4572)
			(end -0.8636 0.4064)
			(stroke
				(width 0.1)
				(type default)
			)
			(layer "F.Fab")
		)
		(fp_line
			(start 0.8636 0.4572)
			(end -0.8636 0.4572)
			(stroke
				(width 0.1)
				(type default)
			)
			(layer "F.Fab")
		)
		(fp_line
			(start -1.1938 0.4064)
			(end -1.1938 -0.4064)
			(stroke
				(width 0.1)
				(type default)
			)
			(layer "F.Fab")
		)
		(fp_line
			(start -0.8636 0.4064)
			(end -1.1938 0.4064)
			(stroke
				(width 0.1)
				(type default)
			)
			(layer "F.Fab")
		)
		(fp_line
			(start 0.8636 0.4064)
			(end 0.8636 0.4572)
			(stroke
				(width 0.1)
				(type default)
			)
			(layer "F.Fab")
		)
		(fp_line
			(start 1.1938 0.4064)
			(end 0.8636 0.4064)
			(stroke
				(width 0.1)
				(type default)
			)
			(layer "F.Fab")
		)
		(fp_line
			(start -1.1938 -0.4064)
			(end -0.8636 -0.4064)
			(stroke
				(width 0.1)
				(type default)
			)
			(layer "F.Fab")
		)
		(fp_line
			(start -0.8636 -0.4064)
			(end -0.8636 -0.4572)
			(stroke
				(width 0.1)
				(type default)
			)
			(layer "F.Fab")
		)
		(fp_line
			(start 0.8636 -0.4064)
			(end 1.1938 -0.4064)
			(stroke
				(width 0.1)
				(type default)
			)
			(layer "F.Fab")
		)
		(fp_line
			(start 1.1938 -0.4064)
			(end 1.1938 0.4064)
			(stroke
				(width 0.1)
				(type default)
			)
			(layer "F.Fab")
		)
		(fp_line
			(start -0.8636 -0.4572)
			(end 0.8636 -0.4572)
			(stroke
				(width 0.1)
				(type default)
			)
			(layer "F.Fab")
		)
		(fp_line
			(start 0.8636 -0.4572)
			(end 0.8636 -0.4064)
			(stroke
				(width 0.1)
				(type default)
			)
			(layer "F.Fab")
		)
		(pad "1" smd rect
			(at -0.7366 0 180)
			(size 0.7112 0.8128)
			(layers "F.Cu" "F.Mask" "F.Paste")
			(net "P0V8_PEX3")
		)
		(pad "2" smd rect
			(at 0.7366 0 180)
			(size 0.7112 0.8128)
			(layers "F.Cu" "F.Mask" "F.Paste")
			(net "GND")
		)
	)
)
